(kicad_pcb
	(version 20260206)
	(generator "pcbnew")
	(generator_version "10.0")
	(general
		(thickness 1.6)
		(legacy_teardrops no)
	)
	(paper "A4")
	(title_block
		(title "Bryce Canyon_SCC_16316-1_OCP.brd")
		(comment 1 "Bryce Canyon / footprints 1034-1041 of 1561")
	)
	(layers
		(0 "F.Cu" signal "TOP")
		(4 "In1.Cu" signal "L2GND")
		(6 "In2.Cu" signal "L3")
		(8 "In3.Cu" signal "L4VCC")
		(10 "In4.Cu" signal "L5VCC")
		(12 "In5.Cu" signal "L6")
		(14 "In6.Cu" signal "L7GND")
		(2 "B.Cu" signal "BOTTOM")
		(9 "F.Adhes" user "F.Adhesive")
		(11 "B.Adhes" user "B.Adhesive")
		(13 "F.Paste" user "Package Geometry/Pastemask Top")
		(15 "B.Paste" user "Package Geometry/Pastemask Bottom")
		(5 "F.SilkS" user "Ref Des/Silkscreen Top")
		(7 "B.SilkS" user "Ref Des/Silkscreen Bottom")
		(1 "F.Mask" user "Board Geometry/Soldermask Top")
		(3 "B.Mask" user "Board Geometry/Soldermask Bottom")
		(17 "Dwgs.User" user "User.Drawings")
		(19 "Cmts.User" user "User.Comments")
		(21 "Eco1.User" user "User.Eco1")
		(23 "Eco2.User" user "User.Eco2")
		(25 "Edge.Cuts" user "Board Geometry/Outline")
		(27 "Margin" user)
		(31 "F.CrtYd" user "Package Geometry/Place Bound Top")
		(29 "B.CrtYd" user "Package Geometry/Place Bound Bottom")
		(35 "F.Fab" user "Ref Des/Assembly Top")
		(33 "B.Fab" user "Ref Des/Assembly Bottom")
	)
	(footprint ""
		(layer "B.Cu")
		(at 107.88523 -59.3217 -90)
		(property "Reference" "C250"
			(at 0 0 90)
			(layer "B.SilkS")
			(hide yes)
			(effects
				(font
					(size 1.27 1.27)
				)
				(justify mirror)
			)
		)
		(property "Value" "SC1U6D3V1MX-GP"
			(at -1.9177 2.0193 270)
			(unlocked yes)
			(layer "B.Fab")
			(hide yes)
			(effects
				(font
					(size 1.016 1.016)
					(thickness 0.1524)
				)
				(justify mirror)
			)
		)
		(property "Device Type" "C0201H14"
			(at -1.9177 0.4953 270)
			(unlocked yes)
			(layer "B.Fab")
			(hide yes)
			(effects
				(font
					(size 1.016 1.016)
					(thickness 0.1524)
				)
				(justify mirror)
			)
		)
		(duplicate_pad_numbers_are_jumpers no)
		(fp_rect
			(start 0.1524 0.3048)
			(end -0.1524 -0.3048)
			(stroke
				(width 0)
				(type default)
			)
			(fill no)
			(layer "B.CrtYd")
		)
		(fp_poly
			(pts
				(xy 0.2794 0.6477) (xy 0.2794 -0.6477) (xy -0.2794 -0.6477) (xy -0.2794 -0.1905) (xy -0.1524 -0.1905)
				(xy -0.1524 -0.3048) (xy 0.1524 -0.3048) (xy 0.1524 0.3048) (xy -0.1524 0.3048) (xy -0.1524 -0.1778)
				(xy -0.2794 -0.1778) (xy -0.2794 0.6477)
			)
			(stroke
				(width 0)
				(type default)
			)
			(fill no)
			(layer "B.CrtYd")
		)
		(fp_rect
			(start 0.2794 0.6477)
			(end -0.2794 -0.6477)
			(stroke
				(width 0)
				(type default)
			)
			(fill no)
			(layer "B.Fab")
		)
		(pad "1" smd custom
			(at 0 -0.2794 90)
			(size 0.0762 0.0762)
			(layers "B.Cu" "B.Mask" "B.Paste")
			(net "GB_VDDA")
			(options
				(clearance outline)
				(anchor circle)
			)
			(primitives
				(gr_poly
					(pts
						(arc
							(start 0.1524 0.127)
							(mid 0.137521 0.162921)
							(end 0.1016 0.1778)
						)
						(arc
							(start -0.1016 0.1778)
							(mid -0.137521 0.162921)
							(end -0.1524 0.127)
						)
						(arc
							(start -0.1524 -0.127)
							(mid -0.137521 -0.162921)
							(end -0.1016 -0.1778)
						)
						(arc
							(start 0.1016 -0.1778)
							(mid 0.137521 -0.162921)
							(end 0.1524 -0.127)
						)
					)
					(width 0)
					(fill yes)
				)
			)
		)
		(pad "2" smd custom
			(at 0 0.2794 90)
			(size 0.0762 0.0762)
			(layers "B.Cu" "B.Mask" "B.Paste")
			(net "GND")
			(options
				(clearance outline)
				(anchor circle)
			)
			(primitives
				(gr_poly
					(pts
						(arc
							(start 0.1524 0.127)
							(mid 0.137521 0.162921)
							(end 0.1016 0.1778)
						)
						(arc
							(start -0.1016 0.1778)
							(mid -0.137521 0.162921)
							(end -0.1524 0.127)
						)
						(arc
							(start -0.1524 -0.127)
							(mid -0.137521 -0.162921)
							(end -0.1016 -0.1778)
						)
						(arc
							(start 0.1016 -0.1778)
							(mid 0.137521 -0.162921)
							(end 0.1524 -0.127)
						)
					)
					(width 0)
					(fill yes)
				)
			)
		)
	)
	(footprint ""
		(layer "B.Cu")
		(at 165.197282 -27.684984 -90)
		(property "Reference" "C387"
			(at 0 0 90)
			(layer "B.SilkS")
			(hide yes)
			(effects
				(font
					(size 1.27 1.27)
				)
				(justify mirror)
			)
		)
		(property "Value" "SCD1U6D3V1KX-GP"
			(at 2.8321 -1.7399 270)
			(unlocked yes)
			(layer "B.Fab")
			(hide yes)
			(effects
				(font
					(size 1.016 1.016)
					(thickness 0.1524)
				)
				(justify mirror)
			)
		)
		(property "Device Type" "C0201H13"
			(at 2.8321 -3.2639 270)
			(unlocked yes)
			(layer "B.Fab")
			(hide yes)
			(effects
				(font
					(size 1.016 1.016)
					(thickness 0.1524)
				)
				(justify mirror)
			)
		)
		(duplicate_pad_numbers_are_jumpers no)
		(fp_rect
			(start 0.2794 0.6477)
			(end -0.2794 -0.6477)
			(stroke
				(width 0)
				(type default)
			)
			(fill no)
			(layer "B.CrtYd")
		)
		(fp_rect
			(start 0.2794 0.6477)
			(end -0.2794 -0.6477)
			(stroke
				(width 0)
				(type default)
			)
			(fill no)
			(layer "B.Fab")
		)
		(pad "1" smd custom
			(at 0 -0.2794 90)
			(size 0.0762 0.0762)
			(layers "B.Cu" "B.Mask" "B.Paste")
			(net "PCE_AVDD")
			(options
				(clearance outline)
				(anchor circle)
			)
			(primitives
				(gr_poly
					(pts
						(arc
							(start 0.1524 0.127)
							(mid 0.137521 0.162921)
							(end 0.1016 0.1778)
						)
						(arc
							(start -0.1016 0.1778)
							(mid -0.137521 0.162921)
							(end -0.1524 0.127)
						)
						(arc
							(start -0.1524 -0.127)
							(mid -0.137521 -0.162921)
							(end -0.1016 -0.1778)
						)
						(arc
							(start 0.1016 -0.1778)
							(mid 0.137521 -0.162921)
							(end 0.1524 -0.127)
						)
					)
					(width 0)
					(fill yes)
				)
			)
		)
		(pad "2" smd custom
			(at 0 0.2794 90)
			(size 0.0762 0.0762)
			(layers "B.Cu" "B.Mask" "B.Paste")
			(net "GND")
			(options
				(clearance outline)
				(anchor circle)
			)
			(primitives
				(gr_poly
					(pts
						(arc
							(start 0.1524 0.127)
							(mid 0.137521 0.162921)
							(end 0.1016 0.1778)
						)
						(arc
							(start -0.1016 0.1778)
							(mid -0.137521 0.162921)
							(end -0.1524 0.127)
						)
						(arc
							(start -0.1524 -0.127)
							(mid -0.137521 -0.162921)
							(end -0.1016 -0.1778)
						)
						(arc
							(start 0.1016 -0.1778)
							(mid 0.137521 -0.162921)
							(end 0.1524 -0.127)
						)
					)
					(width 0)
					(fill yes)
				)
			)
		)
	)
	(footprint ""
		(layer "B.Cu")
		(at 119.507 -44.2214 180)
		(property "Reference" "C58"
			(at 0 0 0)
			(layer "B.SilkS")
			(hide yes)
			(effects
				(font
					(size 1.27 1.27)
				)
				(justify mirror)
			)
		)
		(property "Value" "SCD01U16V1KX-GP"
			(at 2.8321 -1.7399 180)
			(unlocked yes)
			(layer "B.Fab")
			(hide yes)
			(effects
				(font
					(size 1.016 1.016)
					(thickness 0.1524)
				)
				(justify mirror)
			)
		)
		(property "Device Type" "C0201H13"
			(at 2.8321 -3.2639 180)
			(unlocked yes)
			(layer "B.Fab")
			(hide yes)
			(effects
				(font
					(size 1.016 1.016)
					(thickness 0.1524)
				)
				(justify mirror)
			)
		)
		(duplicate_pad_numbers_are_jumpers no)
		(fp_rect
			(start 0.2794 0.6477)
			(end -0.2794 -0.6477)
			(stroke
				(width 0)
				(type default)
			)
			(fill no)
			(layer "B.CrtYd")
		)
		(fp_rect
			(start 0.2794 0.6477)
			(end -0.2794 -0.6477)
			(stroke
				(width 0)
				(type default)
			)
			(fill no)
			(layer "B.Fab")
		)
		(pad "1" smd custom
			(at 0 -0.2794)
			(size 0.0762 0.0762)
			(layers "B.Cu" "B.Mask" "B.Paste")
			(net "PHY_DPB_TO_SCC_35_DN")
			(options
				(clearance outline)
				(anchor circle)
			)
			(primitives
				(gr_poly
					(pts
						(arc
							(start 0.1524 0.127)
							(mid 0.137521 0.162921)
							(end 0.1016 0.1778)
						)
						(arc
							(start -0.1016 0.1778)
							(mid -0.137521 0.162921)
							(end -0.1524 0.127)
						)
						(arc
							(start -0.1524 -0.127)
							(mid -0.137521 -0.162921)
							(end -0.1016 -0.1778)
						)
						(arc
							(start 0.1016 -0.1778)
							(mid 0.137521 -0.162921)
							(end 0.1524 -0.127)
						)
					)
					(width 0)
					(fill yes)
				)
			)
		)
		(pad "2" smd custom
			(at 0 0.2794)
			(size 0.0762 0.0762)
			(layers "B.Cu" "B.Mask" "B.Paste")
			(net "PHY_DPB_TO_SCC_C_35_DN")
			(options
				(clearance outline)
				(anchor circle)
			)
			(primitives
				(gr_poly
					(pts
						(arc
							(start 0.1524 0.127)
							(mid 0.137521 0.162921)
							(end 0.1016 0.1778)
						)
						(arc
							(start -0.1016 0.1778)
							(mid -0.137521 0.162921)
							(end -0.1524 0.127)
						)
						(arc
							(start -0.1524 -0.127)
							(mid -0.137521 -0.162921)
							(end -0.1016 -0.1778)
						)
						(arc
							(start 0.1016 -0.1778)
							(mid 0.137521 -0.162921)
							(end 0.1524 -0.127)
						)
					)
					(width 0)
					(fill yes)
				)
			)
		)
	)
	(footprint ""
		(layer "B.Cu")
		(at 183.170068 -40.05961 -90)
		(property "Reference" "C476"
			(at 0 0 90)
			(layer "B.SilkS")
			(hide yes)
			(effects
				(font
					(size 1.27 1.27)
				)
				(justify mirror)
			)
		)
		(property "Value" "SCD1U6D3V1KX-GP"
			(at 2.8321 -1.7399 270)
			(unlocked yes)
			(layer "B.Fab")
			(hide yes)
			(effects
				(font
					(size 1.016 1.016)
					(thickness 0.1524)
				)
				(justify mirror)
			)
		)
		(property "Device Type" "C0201H13"
			(at 2.8321 -3.2639 270)
			(unlocked yes)
			(layer "B.Fab")
			(hide yes)
			(effects
				(font
					(size 1.016 1.016)
					(thickness 0.1524)
				)
				(justify mirror)
			)
		)
		(duplicate_pad_numbers_are_jumpers no)
		(fp_rect
			(start 0.2794 0.6477)
			(end -0.2794 -0.6477)
			(stroke
				(width 0)
				(type default)
			)
			(fill no)
			(layer "B.CrtYd")
		)
		(fp_rect
			(start 0.2794 0.6477)
			(end -0.2794 -0.6477)
			(stroke
				(width 0)
				(type default)
			)
			(fill no)
			(layer "B.Fab")
		)
		(pad "1" smd custom
			(at 0 -0.2794 90)
			(size 0.0762 0.0762)
			(layers "B.Cu" "B.Mask" "B.Paste")
			(net "P1V8_C")
			(options
				(clearance outline)
				(anchor circle)
			)
			(primitives
				(gr_poly
					(pts
						(arc
							(start 0.1524 0.127)
							(mid 0.137521 0.162921)
							(end 0.1016 0.1778)
						)
						(arc
							(start -0.1016 0.1778)
							(mid -0.137521 0.162921)
							(end -0.1524 0.127)
						)
						(arc
							(start -0.1524 -0.127)
							(mid -0.137521 -0.162921)
							(end -0.1016 -0.1778)
						)
						(arc
							(start 0.1016 -0.1778)
							(mid 0.137521 -0.162921)
							(end 0.1524 -0.127)
						)
					)
					(width 0)
					(fill yes)
				)
			)
		)
		(pad "2" smd custom
			(at 0 0.2794 90)
			(size 0.0762 0.0762)
			(layers "B.Cu" "B.Mask" "B.Paste")
			(net "GND")
			(options
				(clearance outline)
				(anchor circle)
			)
			(primitives
				(gr_poly
					(pts
						(arc
							(start 0.1524 0.127)
							(mid 0.137521 0.162921)
							(end 0.1016 0.1778)
						)
						(arc
							(start -0.1016 0.1778)
							(mid -0.137521 0.162921)
							(end -0.1524 0.127)
						)
						(arc
							(start -0.1524 -0.127)
							(mid -0.137521 -0.162921)
							(end -0.1016 -0.1778)
						)
						(arc
							(start 0.1016 -0.1778)
							(mid 0.137521 -0.162921)
							(end 0.1524 -0.127)
						)
					)
					(width 0)
					(fill yes)
				)
			)
		)
	)
	(footprint ""
		(layer "B.Cu")
		(at 92.15374 -64.04356)
		(property "Reference" "C192"
			(at 0 0 0)
			(layer "B.SilkS")
			(hide yes)
			(effects
				(font
					(size 1.27 1.27)
				)
				(justify mirror)
			)
		)
		(property "Value" "SC22U6D3V3MX-9-GP-U"
			(at 0 -2.8194 0)
			(unlocked yes)
			(layer "B.Fab")
			(hide yes)
			(effects
				(font
					(size 1.016 1.016)
					(thickness 0.1524)
				)
				(justify mirror)
			)
		)
		(property "Device Type" "C603H40"
			(at 0 -4.3434 0)
			(unlocked yes)
			(layer "B.Fab")
			(hide yes)
			(effects
				(font
					(size 1.016 1.016)
					(thickness 0.1524)
				)
				(justify mirror)
			)
		)
		(duplicate_pad_numbers_are_jumpers no)
		(fp_line
			(start -0.508 0)
			(end 0.508 0)
			(stroke
				(width 0.2032)
				(type default)
			)
			(layer "B.SilkS")
		)
		(fp_rect
			(start 0.5842 1.3335)
			(end -0.5842 -1.3335)
			(stroke
				(width 0)
				(type default)
			)
			(fill no)
			(layer "B.CrtYd")
		)
		(fp_rect
			(start 0.5842 1.3335)
			(end -0.5842 -1.3335)
			(stroke
				(width 0)
				(type default)
			)
			(fill no)
			(layer "B.Fab")
		)
		(pad "1" smd custom
			(at 0 -0.762 180)
			(size 0.2159 0.2159)
			(layers "B.Cu" "B.Mask" "B.Paste")
			(net "XTAL_VDDA18")
			(options
				(clearance outline)
				(anchor circle)
			)
			(primitives
				(gr_poly
					(pts
						(arc
							(start -0.3302 0.4318)
							(mid -0.402042 0.402042)
							(end -0.4318 0.3302)
						)
						(arc
							(start -0.4318 -0.3302)
							(mid -0.402042 -0.402042)
							(end -0.3302 -0.4318)
						)
						(arc
							(start 0.3302 -0.4318)
							(mid 0.402042 -0.402042)
							(end 0.4318 -0.3302)
						)
						(arc
							(start 0.4318 0.3302)
							(mid 0.402042 0.402042)
							(end 0.3302 0.4318)
						)
					)
					(width 0)
					(fill yes)
				)
			)
		)
		(pad "2" smd custom
			(at 0 0.762 180)
			(size 0.2159 0.2159)
			(layers "B.Cu" "B.Mask" "B.Paste")
			(net "GND")
			(options
				(clearance outline)
				(anchor circle)
			)
			(primitives
				(gr_poly
					(pts
						(arc
							(start -0.3302 0.4318)
							(mid -0.402042 0.402042)
							(end -0.4318 0.3302)
						)
						(arc
							(start -0.4318 -0.3302)
							(mid -0.402042 -0.402042)
							(end -0.3302 -0.4318)
						)
						(arc
							(start 0.3302 -0.4318)
							(mid 0.402042 -0.402042)
							(end 0.4318 -0.3302)
						)
						(arc
							(start 0.4318 0.3302)
							(mid 0.402042 0.402042)
							(end 0.3302 0.4318)
						)
					)
					(width 0)
					(fill yes)
				)
			)
		)
	)
	(footprint ""
		(layer "B.Cu")
		(at 204.343 -45.80382 180)
		(property "Reference" "C345"
			(at 0 0 0)
			(layer "B.SilkS")
			(hide yes)
			(effects
				(font
					(size 1.27 1.27)
				)
				(justify mirror)
			)
		)
		(property "Value" "SCD1U16V2KX-3GP"
			(at -1.1811 -2.7051 180)
			(unlocked yes)
			(layer "B.Fab")
			(hide yes)
			(effects
				(font
					(size 1.016 1.016)
					(thickness 0.1524)
				)
				(justify mirror)
			)
		)
		(property "Device Type" "C402H22"
			(at -1.1811 -4.2291 180)
			(unlocked yes)
			(layer "B.Fab")
			(hide yes)
			(effects
				(font
					(size 1.016 1.016)
					(thickness 0.1524)
				)
				(justify mirror)
			)
		)
		(duplicate_pad_numbers_are_jumpers no)
		(fp_rect
			(start 0.4318 0.9525)
			(end -0.4318 -0.9525)
			(stroke
				(width 0)
				(type default)
			)
			(fill no)
			(layer "B.CrtYd")
		)
		(fp_rect
			(start 0.4318 0.9525)
			(end -0.4318 -0.9525)
			(stroke
				(width 0)
				(type default)
			)
			(fill no)
			(layer "B.Fab")
		)
		(pad "1" smd custom
			(at 0 -0.4445)
			(size 0.1524 0.1524)
			(layers "B.Cu" "B.Mask" "B.Paste")
			(net "P1V8_C")
			(options
				(clearance outline)
				(anchor circle)
			)
			(primitives
				(gr_poly
					(pts
						(arc
							(start 0.3048 0.2032)
							(mid 0.275042 0.275042)
							(end 0.2032 0.3048)
						)
						(arc
							(start -0.2032 0.3048)
							(mid -0.275042 0.275042)
							(end -0.3048 0.2032)
						)
						(arc
							(start -0.3048 -0.2032)
							(mid -0.275042 -0.275042)
							(end -0.2032 -0.3048)
						)
						(arc
							(start 0.2032 -0.3048)
							(mid 0.275042 -0.275042)
							(end 0.3048 -0.2032)
						)
					)
					(width 0)
					(fill yes)
				)
			)
		)
		(pad "2" smd custom
			(at 0 0.4445)
			(size 0.1524 0.1524)
			(layers "B.Cu" "B.Mask" "B.Paste")
			(net "GND")
			(options
				(clearance outline)
				(anchor circle)
			)
			(primitives
				(gr_poly
					(pts
						(arc
							(start 0.3048 0.2032)
							(mid 0.275042 0.275042)
							(end 0.2032 0.3048)
						)
						(arc
							(start -0.2032 0.3048)
							(mid -0.275042 0.275042)
							(end -0.3048 0.2032)
						)
						(arc
							(start -0.3048 -0.2032)
							(mid -0.275042 -0.275042)
							(end -0.2032 -0.3048)
						)
						(arc
							(start 0.2032 -0.3048)
							(mid 0.275042 -0.275042)
							(end 0.3048 -0.2032)
						)
					)
					(width 0)
					(fill yes)
				)
			)
		)
	)
	(footprint ""
		(layer "B.Cu")
		(at 118.3132 -71.9074)
		(property "Reference" "C143"
			(at 0 0 0)
			(layer "B.SilkS")
			(hide yes)
			(effects
				(font
					(size 1.27 1.27)
				)
				(justify mirror)
			)
		)
		(property "Value" "SCD1U6D3V1KX-GP"
			(at 2.8321 -1.7399 0)
			(unlocked yes)
			(layer "B.Fab")
			(hide yes)
			(effects
				(font
					(size 1.016 1.016)
					(thickness 0.1524)
				)
				(justify mirror)
			)
		)
		(property "Device Type" "C0201H13"
			(at 2.8321 -3.2639 0)
			(unlocked yes)
			(layer "B.Fab")
			(hide yes)
			(effects
				(font
					(size 1.016 1.016)
					(thickness 0.1524)
				)
				(justify mirror)
			)
		)
		(duplicate_pad_numbers_are_jumpers no)
		(fp_rect
			(start 0.2794 0.6477)
			(end -0.2794 -0.6477)
			(stroke
				(width 0)
				(type default)
			)
			(fill no)
			(layer "B.CrtYd")
		)
		(fp_rect
			(start 0.2794 0.6477)
			(end -0.2794 -0.6477)
			(stroke
				(width 0)
				(type default)
			)
			(fill no)
			(layer "B.Fab")
		)
		(pad "1" smd custom
			(at 0 -0.2794 180)
			(size 0.0762 0.0762)
			(layers "B.Cu" "B.Mask" "B.Paste")
			(net "P1V8_E")
			(options
				(clearance outline)
				(anchor circle)
			)
			(primitives
				(gr_poly
					(pts
						(arc
							(start 0.1524 0.127)
							(mid 0.137521 0.162921)
							(end 0.1016 0.1778)
						)
						(arc
							(start -0.1016 0.1778)
							(mid -0.137521 0.162921)
							(end -0.1524 0.127)
						)
						(arc
							(start -0.1524 -0.127)
							(mid -0.137521 -0.162921)
							(end -0.1016 -0.1778)
						)
						(arc
							(start 0.1016 -0.1778)
							(mid 0.137521 -0.162921)
							(end 0.1524 -0.127)
						)
					)
					(width 0)
					(fill yes)
				)
			)
		)
		(pad "2" smd custom
			(at 0 0.2794 180)
			(size 0.0762 0.0762)
			(layers "B.Cu" "B.Mask" "B.Paste")
			(net "GND")
			(options
				(clearance outline)
				(anchor circle)
			)
			(primitives
				(gr_poly
					(pts
						(arc
							(start 0.1524 0.127)
							(mid 0.137521 0.162921)
							(end 0.1016 0.1778)
						)
						(arc
							(start -0.1016 0.1778)
							(mid -0.137521 0.162921)
							(end -0.1524 0.127)
						)
						(arc
							(start -0.1524 -0.127)
							(mid -0.137521 -0.162921)
							(end -0.1016 -0.1778)
						)
						(arc
							(start 0.1016 -0.1778)
							(mid 0.137521 -0.162921)
							(end 0.1524 -0.127)
						)
					)
					(width 0)
					(fill yes)
				)
			)
		)
	)
	(footprint ""
		(layer "B.Cu")
		(at 117.348 -68.6562)
		(property "Reference" "C178"
			(at 0 0 0)
			(layer "B.SilkS")
			(hide yes)
			(effects
				(font
					(size 1.27 1.27)
				)
				(justify mirror)
			)
		)
		(property "Value" "SCD1U6D3V1KX-GP"
			(at 2.8321 -1.7399 0)
			(unlocked yes)
			(layer "B.Fab")
			(hide yes)
			(effects
				(font
					(size 1.016 1.016)
					(thickness 0.1524)
				)
				(justify mirror)
			)
		)
		(property "Device Type" "C0201H13"
			(at 2.8321 -3.2639 0)
			(unlocked yes)
			(layer "B.Fab")
			(hide yes)
			(effects
				(font
					(size 1.016 1.016)
					(thickness 0.1524)
				)
				(justify mirror)
			)
		)
		(duplicate_pad_numbers_are_jumpers no)
		(fp_rect
			(start 0.2794 0.6477)
			(end -0.2794 -0.6477)
			(stroke
				(width 0)
				(type default)
			)
			(fill no)
			(layer "B.CrtYd")
		)
		(fp_rect
			(start 0.2794 0.6477)
			(end -0.2794 -0.6477)
			(stroke
				(width 0)
				(type default)
			)
			(fill no)
			(layer "B.Fab")
		)
		(pad "1" smd custom
			(at 0 -0.2794 180)
			(size 0.0762 0.0762)
			(layers "B.Cu" "B.Mask" "B.Paste")
			(net "P0V9")
			(options
				(clearance outline)
				(anchor circle)
			)
			(primitives
				(gr_poly
					(pts
						(arc
							(start 0.1524 0.127)
							(mid 0.137521 0.162921)
							(end 0.1016 0.1778)
						)
						(arc
							(start -0.1016 0.1778)
							(mid -0.137521 0.162921)
							(end -0.1524 0.127)
						)
						(arc
							(start -0.1524 -0.127)
							(mid -0.137521 -0.162921)
							(end -0.1016 -0.1778)
						)
						(arc
							(start 0.1016 -0.1778)
							(mid 0.137521 -0.162921)
							(end 0.1524 -0.127)
						)
					)
					(width 0)
					(fill yes)
				)
			)
		)
		(pad "2" smd custom
			(at 0 0.2794 180)
			(size 0.0762 0.0762)
			(layers "B.Cu" "B.Mask" "B.Paste")
			(net "GND")
			(options
				(clearance outline)
				(anchor circle)
			)
			(primitives
				(gr_poly
					(pts
						(arc
							(start 0.1524 0.127)
							(mid 0.137521 0.162921)
							(end 0.1016 0.1778)
						)
						(arc
							(start -0.1016 0.1778)
							(mid -0.137521 0.162921)
							(end -0.1524 0.127)
						)
						(arc
							(start -0.1524 -0.127)
							(mid -0.137521 -0.162921)
							(end -0.1016 -0.1778)
						)
						(arc
							(start 0.1016 -0.1778)
							(mid 0.137521 -0.162921)
							(end 0.1524 -0.127)
						)
					)
					(width 0)
					(fill yes)
				)
			)
		)
	)
)
